(kicad_pcb
	(version 20260206)
	(generator "pcbnew")
	(generator_version "10.0")
	(general
		(thickness 1.6)
		(legacy_teardrops no)
	)
	(paper "A4")
	(title_block
		(title "12092022_DA0F0TFB6D0_F0T_FAN_BOARD_MP5048_D_brd_v02_OCP.brd")
		(comment 1 "Grand Teton / footprints 155-160 of 924")
	)
	(layers
		(0 "F.Cu" signal "TOP")
		(4 "In1.Cu" signal "GND")
		(6 "In2.Cu" signal "IN1")
		(8 "In3.Cu" signal "IN2")
		(10 "In4.Cu" signal "GND1")
		(2 "B.Cu" signal "BOTTOM")
		(9 "F.Adhes" user "F.Adhesive")
		(11 "B.Adhes" user "B.Adhesive")
		(13 "F.Paste" user "Package Geometry/Pastemask Top")
		(15 "B.Paste" user "Package Geometry/Pastemask Bottom")
		(5 "F.SilkS" user "Ref Des/Silkscreen Top")
		(7 "B.SilkS" user "Ref Des/Silkscreen Bottom")
		(1 "F.Mask" user "Board Geometry/Soldermask Top")
		(3 "B.Mask" user "Board Geometry/Soldermask Bottom")
		(17 "Dwgs.User" user "User.Drawings")
		(19 "Cmts.User" user "User.Comments")
		(21 "Eco1.User" user "User.Eco1")
		(23 "Eco2.User" user "User.Eco2")
		(25 "Edge.Cuts" user "Board Geometry/Outline")
		(27 "Margin" user)
		(31 "F.CrtYd" user "Package Geometry/Place Bound Top")
		(29 "B.CrtYd" user "Package Geometry/Place Bound Bottom")
		(35 "F.Fab" user "Ref Des/Assembly Top")
		(33 "B.Fab" user "Ref Des/Assembly Bottom")
	)
	(footprint ""
		(layer "F.Cu")
		(at 20.828 -181.61)
		(property "Reference" "R2354"
			(at 0 0 0)
			(layer "F.SilkS")
			(hide yes)
			(effects
				(font
					(size 1.27 1.27)
				)
			)
		)
		(property "Value" ""
			(at 0 0 0)
			(layer "F.Fab")
			(effects
				(font
					(size 1.27 1.27)
				)
			)
		)
		(duplicate_pad_numbers_are_jumpers no)
		(fp_line
			(start -0.7874 -0.4064)
			(end 0.7874 -0.4064)
			(stroke
				(width 0.1524)
				(type default)
			)
			(layer "F.SilkS")
		)
		(fp_line
			(start -0.7874 0.4064)
			(end -0.7874 -0.4064)
			(stroke
				(width 0.1524)
				(type default)
			)
			(layer "F.SilkS")
		)
		(fp_line
			(start 0.7874 -0.4064)
			(end 0.7874 0.4064)
			(stroke
				(width 0.1524)
				(type default)
			)
			(layer "F.SilkS")
		)
		(fp_line
			(start 0.7874 0.4064)
			(end -0.7874 0.4064)
			(stroke
				(width 0.1524)
				(type default)
			)
			(layer "F.SilkS")
		)
		(fp_line
			(start -0.67945 -0.305054)
			(end -0.12065 -0.305054)
			(stroke
				(width 0.1)
				(type default)
			)
			(layer "F.Fab")
		)
		(fp_line
			(start -0.67945 0.3048)
			(end -0.67945 -0.305054)
			(stroke
				(width 0.1)
				(type default)
			)
			(layer "F.Fab")
		)
		(fp_line
			(start -0.12065 -0.305054)
			(end -0.12065 -0.2794)
			(stroke
				(width 0.1)
				(type default)
			)
			(layer "F.Fab")
		)
		(fp_line
			(start -0.12065 -0.2794)
			(end 0.12065 -0.2794)
			(stroke
				(width 0.1)
				(type default)
			)
			(layer "F.Fab")
		)
		(fp_line
			(start -0.12065 0.2794)
			(end -0.12065 0.3048)
			(stroke
				(width 0.1)
				(type default)
			)
			(layer "F.Fab")
		)
		(fp_line
			(start -0.12065 0.3048)
			(end -0.67945 0.3048)
			(stroke
				(width 0.1)
				(type default)
			)
			(layer "F.Fab")
		)
		(fp_line
			(start 0.120396 0.2794)
			(end -0.12065 0.2794)
			(stroke
				(width 0.1)
				(type default)
			)
			(layer "F.Fab")
		)
		(fp_line
			(start 0.120396 0.3048)
			(end 0.120396 0.2794)
			(stroke
				(width 0.1)
				(type default)
			)
			(layer "F.Fab")
		)
		(fp_line
			(start 0.12065 -0.3048)
			(end 0.67945 -0.3048)
			(stroke
				(width 0.1)
				(type default)
			)
			(layer "F.Fab")
		)
		(fp_line
			(start 0.12065 -0.2794)
			(end 0.12065 -0.3048)
			(stroke
				(width 0.1)
				(type default)
			)
			(layer "F.Fab")
		)
		(fp_line
			(start 0.67945 -0.3048)
			(end 0.67945 0.3048)
			(stroke
				(width 0.1)
				(type default)
			)
			(layer "F.Fab")
		)
		(fp_line
			(start 0.67945 0.3048)
			(end 0.120396 0.3048)
			(stroke
				(width 0.1)
				(type default)
			)
			(layer "F.Fab")
		)
		(pad "1" smd circle
			(at -0.40005 0)
			(size 0 0)
			(layers "F.Cu" "F.Mask" "F.Paste")
			(net "PCA9555_MB0_A0")
		)
		(pad "2" smd circle
			(at 0.40005 0)
			(size 0 0)
			(layers "F.Cu" "F.Mask" "F.Paste")
			(net "GND")
		)
	)
	(footprint ""
		(layer "F.Cu")
		(at 20.32 -143.891 90)
		(property "Reference" "R5645"
			(at 0 0 90)
			(layer "F.SilkS")
			(hide yes)
			(effects
				(font
					(size 1.27 1.27)
				)
			)
		)
		(property "Value" ""
			(at 0 0 90)
			(layer "F.Fab")
			(effects
				(font
					(size 1.27 1.27)
				)
			)
		)
		(duplicate_pad_numbers_are_jumpers no)
		(fp_line
			(start 0.7874 -0.4064)
			(end 0.7874 0.4064)
			(stroke
				(width 0.1524)
				(type default)
			)
			(layer "F.SilkS")
		)
		(fp_line
			(start -0.7874 -0.4064)
			(end 0.7874 -0.4064)
			(stroke
				(width 0.1524)
				(type default)
			)
			(layer "F.SilkS")
		)
		(fp_line
			(start 0.7874 0.4064)
			(end -0.7874 0.4064)
			(stroke
				(width 0.1524)
				(type default)
			)
			(layer "F.SilkS")
		)
		(fp_line
			(start -0.7874 0.4064)
			(end -0.7874 -0.4064)
			(stroke
				(width 0.1524)
				(type default)
			)
			(layer "F.SilkS")
		)
		(fp_line
			(start -0.12065 -0.305054)
			(end -0.12065 -0.2794)
			(stroke
				(width 0.1)
				(type default)
			)
			(layer "F.Fab")
		)
		(fp_line
			(start -0.67945 -0.305054)
			(end -0.12065 -0.305054)
			(stroke
				(width 0.1)
				(type default)
			)
			(layer "F.Fab")
		)
		(fp_line
			(start 0.67945 -0.3048)
			(end 0.67945 0.3048)
			(stroke
				(width 0.1)
				(type default)
			)
			(layer "F.Fab")
		)
		(fp_line
			(start 0.12065 -0.3048)
			(end 0.67945 -0.3048)
			(stroke
				(width 0.1)
				(type default)
			)
			(layer "F.Fab")
		)
		(fp_line
			(start 0.12065 -0.2794)
			(end 0.12065 -0.3048)
			(stroke
				(width 0.1)
				(type default)
			)
			(layer "F.Fab")
		)
		(fp_line
			(start -0.12065 -0.2794)
			(end 0.12065 -0.2794)
			(stroke
				(width 0.1)
				(type default)
			)
			(layer "F.Fab")
		)
		(fp_line
			(start 0.120396 0.2794)
			(end -0.12065 0.2794)
			(stroke
				(width 0.1)
				(type default)
			)
			(layer "F.Fab")
		)
		(fp_line
			(start -0.12065 0.2794)
			(end -0.12065 0.3048)
			(stroke
				(width 0.1)
				(type default)
			)
			(layer "F.Fab")
		)
		(fp_line
			(start 0.67945 0.3048)
			(end 0.120396 0.3048)
			(stroke
				(width 0.1)
				(type default)
			)
			(layer "F.Fab")
		)
		(fp_line
			(start 0.120396 0.3048)
			(end 0.120396 0.2794)
			(stroke
				(width 0.1)
				(type default)
			)
			(layer "F.Fab")
		)
		(fp_line
			(start -0.12065 0.3048)
			(end -0.67945 0.3048)
			(stroke
				(width 0.1)
				(type default)
			)
			(layer "F.Fab")
		)
		(fp_line
			(start -0.67945 0.3048)
			(end -0.67945 -0.305054)
			(stroke
				(width 0.1)
				(type default)
			)
			(layer "F.Fab")
		)
		(pad "1" smd circle
			(at -0.40005 0 90)
			(size 0 0)
			(layers "F.Cu" "F.Mask" "F.Paste")
			(net "RST_SMB_PDB_N")
		)
		(pad "2" smd circle
			(at 0.40005 0 90)
			(size 0 0)
			(layers "F.Cu" "F.Mask" "F.Paste")
			(net "RST_SMB_PDB_R_N")
		)
	)
	(footprint ""
		(layer "F.Cu")
		(at 46.355 -168.529)
		(property "Reference" "R5117"
			(at 0 0 0)
			(layer "F.SilkS")
			(hide yes)
			(effects
				(font
					(size 1.27 1.27)
				)
			)
		)
		(property "Value" ""
			(at 0 0 0)
			(layer "F.Fab")
			(effects
				(font
					(size 1.27 1.27)
				)
			)
		)
		(duplicate_pad_numbers_are_jumpers no)
		(fp_line
			(start -0.7874 -0.4064)
			(end 0.7874 -0.4064)
			(stroke
				(width 0.1524)
				(type default)
			)
			(layer "F.SilkS")
		)
		(fp_line
			(start -0.7874 0.4064)
			(end -0.7874 -0.4064)
			(stroke
				(width 0.1524)
				(type default)
			)
			(layer "F.SilkS")
		)
		(fp_line
			(start 0.7874 -0.4064)
			(end 0.7874 0.4064)
			(stroke
				(width 0.1524)
				(type default)
			)
			(layer "F.SilkS")
		)
		(fp_line
			(start 0.7874 0.4064)
			(end -0.7874 0.4064)
			(stroke
				(width 0.1524)
				(type default)
			)
			(layer "F.SilkS")
		)
		(fp_line
			(start -0.67945 -0.305054)
			(end -0.12065 -0.305054)
			(stroke
				(width 0.1)
				(type default)
			)
			(layer "F.Fab")
		)
		(fp_line
			(start -0.67945 0.3048)
			(end -0.67945 -0.305054)
			(stroke
				(width 0.1)
				(type default)
			)
			(layer "F.Fab")
		)
		(fp_line
			(start -0.12065 -0.305054)
			(end -0.12065 -0.2794)
			(stroke
				(width 0.1)
				(type default)
			)
			(layer "F.Fab")
		)
		(fp_line
			(start -0.12065 -0.2794)
			(end 0.12065 -0.2794)
			(stroke
				(width 0.1)
				(type default)
			)
			(layer "F.Fab")
		)
		(fp_line
			(start -0.12065 0.2794)
			(end -0.12065 0.3048)
			(stroke
				(width 0.1)
				(type default)
			)
			(layer "F.Fab")
		)
		(fp_line
			(start -0.12065 0.3048)
			(end -0.67945 0.3048)
			(stroke
				(width 0.1)
				(type default)
			)
			(layer "F.Fab")
		)
		(fp_line
			(start 0.120396 0.2794)
			(end -0.12065 0.2794)
			(stroke
				(width 0.1)
				(type default)
			)
			(layer "F.Fab")
		)
		(fp_line
			(start 0.120396 0.3048)
			(end 0.120396 0.2794)
			(stroke
				(width 0.1)
				(type default)
			)
			(layer "F.Fab")
		)
		(fp_line
			(start 0.12065 -0.3048)
			(end 0.67945 -0.3048)
			(stroke
				(width 0.1)
				(type default)
			)
			(layer "F.Fab")
		)
		(fp_line
			(start 0.12065 -0.2794)
			(end 0.12065 -0.3048)
			(stroke
				(width 0.1)
				(type default)
			)
			(layer "F.Fab")
		)
		(fp_line
			(start 0.67945 -0.3048)
			(end 0.67945 0.3048)
			(stroke
				(width 0.1)
				(type default)
			)
			(layer "F.Fab")
		)
		(fp_line
			(start 0.67945 0.3048)
			(end 0.120396 0.3048)
			(stroke
				(width 0.1)
				(type default)
			)
			(layer "F.Fab")
		)
		(pad "1" smd circle
			(at -0.40005 0)
			(size 0 0)
			(layers "F.Cu" "F.Mask" "F.Paste")
			(net "PCA9552_MB1_A2")
		)
		(pad "2" smd circle
			(at 0.40005 0)
			(size 0 0)
			(layers "F.Cu" "F.Mask" "F.Paste")
			(net "GND")
		)
	)
	(footprint ""
		(layer "F.Cu")
		(at 20.828 -178.816)
		(property "Reference" "R5687"
			(at 0 0 0)
			(layer "F.SilkS")
			(hide yes)
			(effects
				(font
					(size 1.27 1.27)
				)
			)
		)
		(property "Value" ""
			(at 0 0 0)
			(layer "F.Fab")
			(effects
				(font
					(size 1.27 1.27)
				)
			)
		)
		(duplicate_pad_numbers_are_jumpers no)
		(fp_line
			(start -0.7874 -0.4064)
			(end 0.7874 -0.4064)
			(stroke
				(width 0.1524)
				(type default)
			)
			(layer "F.SilkS")
		)
		(fp_line
			(start -0.7874 0.4064)
			(end -0.7874 -0.4064)
			(stroke
				(width 0.1524)
				(type default)
			)
			(layer "F.SilkS")
		)
		(fp_line
			(start 0.7874 -0.4064)
			(end 0.7874 0.4064)
			(stroke
				(width 0.1524)
				(type default)
			)
			(layer "F.SilkS")
		)
		(fp_line
			(start 0.7874 0.4064)
			(end -0.7874 0.4064)
			(stroke
				(width 0.1524)
				(type default)
			)
			(layer "F.SilkS")
		)
		(fp_line
			(start -0.67945 -0.305054)
			(end -0.12065 -0.305054)
			(stroke
				(width 0.1)
				(type default)
			)
			(layer "F.Fab")
		)
		(fp_line
			(start -0.67945 0.3048)
			(end -0.67945 -0.305054)
			(stroke
				(width 0.1)
				(type default)
			)
			(layer "F.Fab")
		)
		(fp_line
			(start -0.12065 -0.305054)
			(end -0.12065 -0.2794)
			(stroke
				(width 0.1)
				(type default)
			)
			(layer "F.Fab")
		)
		(fp_line
			(start -0.12065 -0.2794)
			(end 0.12065 -0.2794)
			(stroke
				(width 0.1)
				(type default)
			)
			(layer "F.Fab")
		)
		(fp_line
			(start -0.12065 0.2794)
			(end -0.12065 0.3048)
			(stroke
				(width 0.1)
				(type default)
			)
			(layer "F.Fab")
		)
		(fp_line
			(start -0.12065 0.3048)
			(end -0.67945 0.3048)
			(stroke
				(width 0.1)
				(type default)
			)
			(layer "F.Fab")
		)
		(fp_line
			(start 0.120396 0.2794)
			(end -0.12065 0.2794)
			(stroke
				(width 0.1)
				(type default)
			)
			(layer "F.Fab")
		)
		(fp_line
			(start 0.120396 0.3048)
			(end 0.120396 0.2794)
			(stroke
				(width 0.1)
				(type default)
			)
			(layer "F.Fab")
		)
		(fp_line
			(start 0.12065 -0.3048)
			(end 0.67945 -0.3048)
			(stroke
				(width 0.1)
				(type default)
			)
			(layer "F.Fab")
		)
		(fp_line
			(start 0.12065 -0.2794)
			(end 0.12065 -0.3048)
			(stroke
				(width 0.1)
				(type default)
			)
			(layer "F.Fab")
		)
		(fp_line
			(start 0.67945 -0.3048)
			(end 0.67945 0.3048)
			(stroke
				(width 0.1)
				(type default)
			)
			(layer "F.Fab")
		)
		(fp_line
			(start 0.67945 0.3048)
			(end 0.120396 0.3048)
			(stroke
				(width 0.1)
				(type default)
			)
			(layer "F.Fab")
		)
		(pad "1" smd circle
			(at -0.40005 0)
			(size 0 0)
			(layers "F.Cu" "F.Mask" "F.Paste")
			(net "FM_BOARD_ID1")
		)
		(pad "2" smd circle
			(at 0.40005 0)
			(size 0 0)
			(layers "F.Cu" "F.Mask" "F.Paste")
			(net "GND")
		)
	)
	(footprint ""
		(layer "F.Cu")
		(at 14.351 -293.624 180)
		(property "Reference" "R5697"
			(at 0 0 180)
			(layer "F.SilkS")
			(hide yes)
			(effects
				(font
					(size 1.27 1.27)
				)
			)
		)
		(property "Value" ""
			(at 0 0 180)
			(layer "F.Fab")
			(effects
				(font
					(size 1.27 1.27)
				)
			)
		)
		(duplicate_pad_numbers_are_jumpers no)
		(fp_line
			(start 0.7874 0.4064)
			(end -0.7874 0.4064)
			(stroke
				(width 0.1524)
				(type default)
			)
			(layer "F.SilkS")
		)
		(fp_line
			(start 0.7874 -0.4064)
			(end 0.7874 0.4064)
			(stroke
				(width 0.1524)
				(type default)
			)
			(layer "F.SilkS")
		)
		(fp_line
			(start -0.7874 0.4064)
			(end -0.7874 -0.4064)
			(stroke
				(width 0.1524)
				(type default)
			)
			(layer "F.SilkS")
		)
		(fp_line
			(start -0.7874 -0.4064)
			(end 0.7874 -0.4064)
			(stroke
				(width 0.1524)
				(type default)
			)
			(layer "F.SilkS")
		)
		(fp_line
			(start 0.67945 0.3048)
			(end 0.120396 0.3048)
			(stroke
				(width 0.1)
				(type default)
			)
			(layer "F.Fab")
		)
		(fp_line
			(start 0.67945 -0.3048)
			(end 0.67945 0.3048)
			(stroke
				(width 0.1)
				(type default)
			)
			(layer "F.Fab")
		)
		(fp_line
			(start 0.12065 -0.2794)
			(end 0.12065 -0.3048)
			(stroke
				(width 0.1)
				(type default)
			)
			(layer "F.Fab")
		)
		(fp_line
			(start 0.12065 -0.3048)
			(end 0.67945 -0.3048)
			(stroke
				(width 0.1)
				(type default)
			)
			(layer "F.Fab")
		)
		(fp_line
			(start 0.120396 0.3048)
			(end 0.120396 0.2794)
			(stroke
				(width 0.1)
				(type default)
			)
			(layer "F.Fab")
		)
		(fp_line
			(start 0.120396 0.2794)
			(end -0.12065 0.2794)
			(stroke
				(width 0.1)
				(type default)
			)
			(layer "F.Fab")
		)
		(fp_line
			(start -0.12065 0.3048)
			(end -0.67945 0.3048)
			(stroke
				(width 0.1)
				(type default)
			)
			(layer "F.Fab")
		)
		(fp_line
			(start -0.12065 0.2794)
			(end -0.12065 0.3048)
			(stroke
				(width 0.1)
				(type default)
			)
			(layer "F.Fab")
		)
		(fp_line
			(start -0.12065 -0.2794)
			(end 0.12065 -0.2794)
			(stroke
				(width 0.1)
				(type default)
			)
			(layer "F.Fab")
		)
		(fp_line
			(start -0.12065 -0.305054)
			(end -0.12065 -0.2794)
			(stroke
				(width 0.1)
				(type default)
			)
			(layer "F.Fab")
		)
		(fp_line
			(start -0.67945 0.3048)
			(end -0.67945 -0.305054)
			(stroke
				(width 0.1)
				(type default)
			)
			(layer "F.Fab")
		)
		(fp_line
			(start -0.67945 -0.305054)
			(end -0.12065 -0.305054)
			(stroke
				(width 0.1)
				(type default)
			)
			(layer "F.Fab")
		)
		(pad "1" smd rect
			(at -0.40005 0)
			(size 0.4572 0.508)
			(layers "F.Cu" "F.Mask" "F.Paste")
			(net "P12V_LED_FAN7")
		)
		(pad "2" smd rect
			(at 0.40005 0)
			(size 0.4572 0.508)
			(layers "F.Cu" "F.Mask" "F.Paste")
			(net "P12V_LED_R_FAN7")
		)
	)
	(footprint ""
		(layer "F.Cu")
		(at 37.338 -293.624)
		(property "Reference" "R5414"
			(at 0 0 0)
			(layer "F.SilkS")
			(hide yes)
			(effects
				(font
					(size 1.27 1.27)
				)
			)
		)
		(property "Value" ""
			(at 0 0 0)
			(layer "F.Fab")
			(effects
				(font
					(size 1.27 1.27)
				)
			)
		)
		(duplicate_pad_numbers_are_jumpers no)
		(fp_line
			(start -0.7874 -0.4064)
			(end 0.7874 -0.4064)
			(stroke
				(width 0.1524)
				(type default)
			)
			(layer "F.SilkS")
		)
		(fp_line
			(start -0.7874 0.4064)
			(end -0.7874 -0.4064)
			(stroke
				(width 0.1524)
				(type default)
			)
			(layer "F.SilkS")
		)
		(fp_line
			(start 0.7874 -0.4064)
			(end 0.7874 0.4064)
			(stroke
				(width 0.1524)
				(type default)
			)
			(layer "F.SilkS")
		)
		(fp_line
			(start 0.7874 0.4064)
			(end -0.7874 0.4064)
			(stroke
				(width 0.1524)
				(type default)
			)
			(layer "F.SilkS")
		)
		(fp_line
			(start -0.67945 -0.305054)
			(end -0.12065 -0.305054)
			(stroke
				(width 0.1)
				(type default)
			)
			(layer "F.Fab")
		)
		(fp_line
			(start -0.67945 0.3048)
			(end -0.67945 -0.305054)
			(stroke
				(width 0.1)
				(type default)
			)
			(layer "F.Fab")
		)
		(fp_line
			(start -0.12065 -0.305054)
			(end -0.12065 -0.2794)
			(stroke
				(width 0.1)
				(type default)
			)
			(layer "F.Fab")
		)
		(fp_line
			(start -0.12065 -0.2794)
			(end 0.12065 -0.2794)
			(stroke
				(width 0.1)
				(type default)
			)
			(layer "F.Fab")
		)
		(fp_line
			(start -0.12065 0.2794)
			(end -0.12065 0.3048)
			(stroke
				(width 0.1)
				(type default)
			)
			(layer "F.Fab")
		)
		(fp_line
			(start -0.12065 0.3048)
			(end -0.67945 0.3048)
			(stroke
				(width 0.1)
				(type default)
			)
			(layer "F.Fab")
		)
		(fp_line
			(start 0.120396 0.2794)
			(end -0.12065 0.2794)
			(stroke
				(width 0.1)
				(type default)
			)
			(layer "F.Fab")
		)
		(fp_line
			(start 0.120396 0.3048)
			(end 0.120396 0.2794)
			(stroke
				(width 0.1)
				(type default)
			)
			(layer "F.Fab")
		)
		(fp_line
			(start 0.12065 -0.3048)
			(end 0.67945 -0.3048)
			(stroke
				(width 0.1)
				(type default)
			)
			(layer "F.Fab")
		)
		(fp_line
			(start 0.12065 -0.2794)
			(end 0.12065 -0.3048)
			(stroke
				(width 0.1)
				(type default)
			)
			(layer "F.Fab")
		)
		(fp_line
			(start 0.67945 -0.3048)
			(end 0.67945 0.3048)
			(stroke
				(width 0.1)
				(type default)
			)
			(layer "F.Fab")
		)
		(fp_line
			(start 0.67945 0.3048)
			(end 0.120396 0.3048)
			(stroke
				(width 0.1)
				(type default)
			)
			(layer "F.Fab")
		)
		(pad "1" smd rect
			(at -0.40005 0 180)
			(size 0.4572 0.508)
			(layers "F.Cu" "F.Mask" "F.Paste")
			(net "FAN_0_FAIL_LED_R_N")
		)
		(pad "2" smd rect
			(at 0.40005 0 180)
			(size 0.4572 0.508)
			(layers "F.Cu" "F.Mask" "F.Paste")
			(net "FAN_0_FAIL_R_LED_N")
		)
	)
)
